# S9S_MB_2U (Grand Teton) — schematic netlist excerpt (pin names and nets, part order shuffled) for the footprints in the layout excerpt that follows; sources: Cadence DE-HDL packaged netlist, KiCad conversion of 03242023_DA0F0TMBIJ0_F0T_Motherboard_J_brd_V01_OCP.brd

C506  Q_CAP  47UF 4V 20% X6S  pkg C0805  page 76 : A = PVCCFA_EHV_FIVRA_CPU0 ; B = GND
R1204  Q_RES  10K 1% EMPTY  pkg 0402LF  page 208 : A = P3V3_AUX ; B = PU_CK440_SHFT_LD_N
R421  Q_RES  10K 1% CHIP  pkg 0402LF  page 153 : A = SGPIO_OCP_SFF_DATAIN ; B = P3V3_OCP_SFF

(kicad_pcb
	(version 20260206)
	(generator "pcbnew")
	(generator_version "10.0")
	(general
		(thickness 1.6)
		(legacy_teardrops no)
	)
	(paper "A4")
	(title_block
		(title "03242023_DA0F0TMBIJ0_F0T_Motherboard_J_brd_V01_OCP.brd")
		(comment 1 "Grand Teton / footprints 5742-5744 of 6105")
	)
	(layers
		(0 "F.Cu" signal "TOP")
		(4 "In1.Cu" signal "GND")
		(6 "In2.Cu" signal "IN1")
		(8 "In3.Cu" signal "GND1")
		(10 "In4.Cu" signal "IN2")
		(12 "In5.Cu" signal "GND2")
		(14 "In6.Cu" signal "IN3")
		(16 "In7.Cu" signal "GND3")
		(18 "In8.Cu" signal "VCC")
		(20 "In9.Cu" signal "VCC1")
		(22 "In10.Cu" signal "GND4")
		(24 "In11.Cu" signal "IN4")
		(26 "In12.Cu" signal "GND5")
		(28 "In13.Cu" signal "IN5")
		(30 "In14.Cu" signal "GND6")
		(32 "In15.Cu" signal "IN6")
		(34 "In16.Cu" signal "GND7")
		(2 "B.Cu" signal "BOTTOM")
		(9 "F.Adhes" user "F.Adhesive")
		(11 "B.Adhes" user "B.Adhesive")
		(13 "F.Paste" user "Package Geometry/Pastemask Top")
		(15 "B.Paste" user "Package Geometry/Pastemask Bottom")
		(5 "F.SilkS" user "Ref Des/Silkscreen Top")
		(7 "B.SilkS" user "Ref Des/Silkscreen Bottom")
		(1 "F.Mask" user "Board Geometry/Soldermask Top")
		(3 "B.Mask" user "Board Geometry/Soldermask Bottom")
		(17 "Dwgs.User" user "User.Drawings")
		(19 "Cmts.User" user "User.Comments")
		(21 "Eco1.User" user "User.Eco1")
		(23 "Eco2.User" user "User.Eco2")
		(25 "Edge.Cuts" user "Board Geometry/Outline")
		(27 "Margin" user)
		(31 "F.CrtYd" user "Package Geometry/Place Bound Top")
		(29 "B.CrtYd" user "Package Geometry/Place Bound Bottom")
		(35 "F.Fab" user "Ref Des/Assembly Top")
		(33 "B.Fab" user "Ref Des/Assembly Bottom")
	)
	(footprint ""
		(layer "B.Cu")
		(at 451.549516 -10.634726 90)
		(property "Reference" "R421"
			(at 0 0 90)
			(layer "B.SilkS")
			(hide yes)
			(effects
				(font
					(size 1.27 1.27)
				)
				(justify mirror)
			)
		)
		(property "Value" ""
			(at 0 0 90)
			(layer "B.Fab")
			(effects
				(font
					(size 1.27 1.27)
				)
				(justify mirror)
			)
		)
		(duplicate_pad_numbers_are_jumpers no)
		(fp_line
			(start 0.7874 -0.4064)
			(end -0.7874 -0.4064)
			(stroke
				(width 0.1524)
				(type default)
			)
			(layer "B.SilkS")
		)
		(fp_line
			(start -0.7874 -0.4064)
			(end -0.7874 0.4064)
			(stroke
				(width 0.1524)
				(type default)
			)
			(layer "B.SilkS")
		)
		(fp_line
			(start 0.7874 0.4064)
			(end 0.7874 -0.4064)
			(stroke
				(width 0.1524)
				(type default)
			)
			(layer "B.SilkS")
		)
		(fp_line
			(start -0.7874 0.4064)
			(end 0.7874 0.4064)
			(stroke
				(width 0.1524)
				(type default)
			)
			(layer "B.SilkS")
		)
		(fp_line
			(start 0.67945 -0.305054)
			(end 0.12065 -0.305054)
			(stroke
				(width 0.1)
				(type default)
			)
			(layer "B.Fab")
		)
		(fp_line
			(start 0.12065 -0.305054)
			(end 0.12065 -0.2794)
			(stroke
				(width 0.1)
				(type default)
			)
			(layer "B.Fab")
		)
		(fp_line
			(start -0.12065 -0.3048)
			(end -0.67945 -0.3048)
			(stroke
				(width 0.1)
				(type default)
			)
			(layer "B.Fab")
		)
		(fp_line
			(start -0.67945 -0.3048)
			(end -0.67945 0.3048)
			(stroke
				(width 0.1)
				(type default)
			)
			(layer "B.Fab")
		)
		(fp_line
			(start 0.12065 -0.2794)
			(end -0.12065 -0.2794)
			(stroke
				(width 0.1)
				(type default)
			)
			(layer "B.Fab")
		)
		(fp_line
			(start -0.12065 -0.2794)
			(end -0.12065 -0.3048)
			(stroke
				(width 0.1)
				(type default)
			)
			(layer "B.Fab")
		)
		(fp_line
			(start 0.12065 0.2794)
			(end 0.12065 0.3048)
			(stroke
				(width 0.1)
				(type default)
			)
			(layer "B.Fab")
		)
		(fp_line
			(start -0.120396 0.2794)
			(end 0.12065 0.2794)
			(stroke
				(width 0.1)
				(type default)
			)
			(layer "B.Fab")
		)
		(fp_line
			(start 0.67945 0.3048)
			(end 0.67945 -0.305054)
			(stroke
				(width 0.1)
				(type default)
			)
			(layer "B.Fab")
		)
		(fp_line
			(start 0.12065 0.3048)
			(end 0.67945 0.3048)
			(stroke
				(width 0.1)
				(type default)
			)
			(layer "B.Fab")
		)
		(fp_line
			(start -0.120396 0.3048)
			(end -0.120396 0.2794)
			(stroke
				(width 0.1)
				(type default)
			)
			(layer "B.Fab")
		)
		(fp_line
			(start -0.67945 0.3048)
			(end -0.120396 0.3048)
			(stroke
				(width 0.1)
				(type default)
			)
			(layer "B.Fab")
		)
		(pad "1" smd circle
			(at 0.40005 0 270)
			(size 0 0)
			(layers "B.Cu" "B.Mask" "B.Paste")
			(net "SGPIO_OCP_SFF_DATAIN")
		)
		(pad "2" smd circle
			(at -0.40005 0 270)
			(size 0 0)
			(layers "B.Cu" "B.Mask" "B.Paste")
			(net "P3V3_OCP_SFF")
		)
	)
	(footprint ""
		(layer "B.Cu")
		(at 254.824484 -106.467148)
		(property "Reference" "R1204"
			(at 0 0 0)
			(layer "B.SilkS")
			(hide yes)
			(effects
				(font
					(size 1.27 1.27)
				)
				(justify mirror)
			)
		)
		(property "Value" ""
			(at 0 0 0)
			(layer "B.Fab")
			(effects
				(font
					(size 1.27 1.27)
				)
				(justify mirror)
			)
		)
		(duplicate_pad_numbers_are_jumpers no)
		(fp_line
			(start -0.7874 -0.4064)
			(end -0.7874 0.4064)
			(stroke
				(width 0.1524)
				(type default)
			)
			(layer "B.SilkS")
		)
		(fp_line
			(start -0.7874 0.4064)
			(end 0.7874 0.4064)
			(stroke
				(width 0.1524)
				(type default)
			)
			(layer "B.SilkS")
		)
		(fp_line
			(start 0.7874 -0.4064)
			(end -0.7874 -0.4064)
			(stroke
				(width 0.1524)
				(type default)
			)
			(layer "B.SilkS")
		)
		(fp_line
			(start 0.7874 0.4064)
			(end 0.7874 -0.4064)
			(stroke
				(width 0.1524)
				(type default)
			)
			(layer "B.SilkS")
		)
		(fp_line
			(start -0.67945 -0.3048)
			(end -0.67945 0.3048)
			(stroke
				(width 0.1)
				(type default)
			)
			(layer "B.Fab")
		)
		(fp_line
			(start -0.67945 0.3048)
			(end -0.120396 0.3048)
			(stroke
				(width 0.1)
				(type default)
			)
			(layer "B.Fab")
		)
		(fp_line
			(start -0.12065 -0.3048)
			(end -0.67945 -0.3048)
			(stroke
				(width 0.1)
				(type default)
			)
			(layer "B.Fab")
		)
		(fp_line
			(start -0.12065 -0.2794)
			(end -0.12065 -0.3048)
			(stroke
				(width 0.1)
				(type default)
			)
			(layer "B.Fab")
		)
		(fp_line
			(start -0.120396 0.2794)
			(end 0.12065 0.2794)
			(stroke
				(width 0.1)
				(type default)
			)
			(layer "B.Fab")
		)
		(fp_line
			(start -0.120396 0.3048)
			(end -0.120396 0.2794)
			(stroke
				(width 0.1)
				(type default)
			)
			(layer "B.Fab")
		)
		(fp_line
			(start 0.12065 -0.305054)
			(end 0.12065 -0.2794)
			(stroke
				(width 0.1)
				(type default)
			)
			(layer "B.Fab")
		)
		(fp_line
			(start 0.12065 -0.2794)
			(end -0.12065 -0.2794)
			(stroke
				(width 0.1)
				(type default)
			)
			(layer "B.Fab")
		)
		(fp_line
			(start 0.12065 0.2794)
			(end 0.12065 0.3048)
			(stroke
				(width 0.1)
				(type default)
			)
			(layer "B.Fab")
		)
		(fp_line
			(start 0.12065 0.3048)
			(end 0.67945 0.3048)
			(stroke
				(width 0.1)
				(type default)
			)
			(layer "B.Fab")
		)
		(fp_line
			(start 0.67945 -0.305054)
			(end 0.12065 -0.305054)
			(stroke
				(width 0.1)
				(type default)
			)
			(layer "B.Fab")
		)
		(fp_line
			(start 0.67945 0.3048)
			(end 0.67945 -0.305054)
			(stroke
				(width 0.1)
				(type default)
			)
			(layer "B.Fab")
		)
		(pad "1" smd circle
			(at 0.40005 0 180)
			(size 0 0)
			(layers "B.Cu" "B.Mask" "B.Paste")
			(net "P3V3_AUX")
		)
		(pad "2" smd circle
			(at -0.40005 0 180)
			(size 0 0)
			(layers "B.Cu" "B.Mask" "B.Paste")
			(net "PU_CK440_SHFT_LD_N")
		)
	)
	(footprint ""
		(layer "B.Cu")
		(at 410.851604 -250.791218 90)
		(property "Reference" "C506"
			(at 0 0 90)
			(layer "B.SilkS")
			(hide yes)
			(effects
				(font
					(size 1.27 1.27)
				)
				(justify mirror)
			)
		)
		(property "Value" ""
			(at 0 0 90)
			(layer "B.Fab")
			(effects
				(font
					(size 1.27 1.27)
				)
				(justify mirror)
			)
		)
		(duplicate_pad_numbers_are_jumpers no)
		(fp_line
			(start 1.524 -0.762)
			(end -1.524 -0.762)
			(stroke
				(width 0.1524)
				(type default)
			)
			(layer "B.SilkS")
		)
		(fp_line
			(start -1.524 -0.762)
			(end -1.524 0.762)
			(stroke
				(width 0.1524)
				(type default)
			)
			(layer "B.SilkS")
		)
		(fp_line
			(start 1.524 0.762)
			(end 1.524 -0.762)
			(stroke
				(width 0.1524)
				(type default)
			)
			(layer "B.SilkS")
		)
		(fp_line
			(start -1.524 0.762)
			(end 1.524 0.762)
			(stroke
				(width 0.1524)
				(type default)
			)
			(layer "B.SilkS")
		)
		(fp_line
			(start 1.1049 -0.724916)
			(end 1.1049 0.724916)
			(stroke
				(width 0.1)
				(type default)
			)
			(layer "B.Fab")
		)
		(fp_line
			(start -1.1049 -0.724916)
			(end 1.1049 -0.724916)
			(stroke
				(width 0.1)
				(type default)
			)
			(layer "B.Fab")
		)
		(fp_line
			(start 1.1049 0.724916)
			(end -1.1049 0.724916)
			(stroke
				(width 0.1)
				(type default)
			)
			(layer "B.Fab")
		)
		(fp_line
			(start -1.1049 0.724916)
			(end -1.1049 -0.724916)
			(stroke
				(width 0.1)
				(type default)
			)
			(layer "B.Fab")
		)
		(pad "1" smd rect
			(at 0.889 0 90)
			(size 1.016 1.27)
			(layers "B.Cu" "B.Mask" "B.Paste")
			(net "PVCCFA_EHV_FIVRA_CPU0")
		)
		(pad "2" smd rect
			(at -0.889 0 90)
			(size 1.016 1.27)
			(layers "B.Cu" "B.Mask" "B.Paste")
			(net "GND")
		)
	)
)
